(kicad_pcb
	(version 20260206)
	(generator "pcbnew")
	(generator_version "10.0")
	(general
		(thickness 1.6)
		(legacy_teardrops no)
	)
	(paper "A4")
	(title_block
		(title "pdpb — Lightning_PDPB_BRD.brd")
		(comment 1 "Lightning (Wiwynn / Facebook NVMe JBOF) / footprints 416-422 of 1140")
	)
	(layers
		(0 "F.Cu" signal "TOP")
		(4 "In1.Cu" signal "L2GND")
		(6 "In2.Cu" signal "L3")
		(8 "In3.Cu" signal "L4VCC")
		(10 "In4.Cu" signal "L5VCC")
		(12 "In5.Cu" signal "L6")
		(14 "In6.Cu" signal "L7GND")
		(2 "B.Cu" signal "BOTTOM")
		(9 "F.Adhes" user "F.Adhesive")
		(11 "B.Adhes" user "B.Adhesive")
		(13 "F.Paste" user "Package Geometry/Pastemask Top")
		(15 "B.Paste" user "Package Geometry/Pastemask Bottom")
		(5 "F.SilkS" user "Ref Des/Silkscreen Top")
		(7 "B.SilkS" user "Ref Des/Silkscreen Bottom")
		(1 "F.Mask" user "Board Geometry/Soldermask Top")
		(3 "B.Mask" user "Board Geometry/Soldermask Bottom")
		(17 "Dwgs.User" user "User.Drawings")
		(19 "Cmts.User" user "User.Comments")
		(21 "Eco1.User" user "User.Eco1")
		(23 "Eco2.User" user "User.Eco2")
		(25 "Edge.Cuts" user "Board Geometry/Outline")
		(27 "Margin" user)
		(31 "F.CrtYd" user "Package Geometry/Place Bound Top")
		(29 "B.CrtYd" user "Package Geometry/Place Bound Bottom")
		(35 "F.Fab" user "Ref Des/Assembly Top")
		(33 "B.Fab" user "Ref Des/Assembly Bottom")
	)
	(footprint ""
		(layer "F.Cu")
		(at 89.789 -116.586 90)
		(property "Reference" "R9423"
			(at 0 0 90)
			(layer "F.SilkS")
			(hide yes)
			(effects
				(font
					(size 1.27 1.27)
				)
			)
		)
		(property "Value" "4K7R2J-2-GP"
			(at 0.064008 -3.993896 90)
			(unlocked yes)
			(layer "F.Fab")
			(hide yes)
			(effects
				(font
					(size 1.016 1.016)
					(thickness 0.1524)
				)
			)
		)
		(property "Device Type" "R402H16"
			(at 0.064008 -5.517896 90)
			(unlocked yes)
			(layer "F.Fab")
			(hide yes)
			(effects
				(font
					(size 1.016 1.016)
					(thickness 0.1524)
				)
			)
		)
		(duplicate_pad_numbers_are_jumpers no)
		(fp_line
			(start 0.508 -0.9398)
			(end -0.508 -0.9398)
			(stroke
				(width 0.1524)
				(type default)
			)
			(layer "F.SilkS")
		)
		(fp_line
			(start -0.508 -0.9398)
			(end -0.508 0.9398)
			(stroke
				(width 0.1524)
				(type default)
			)
			(layer "F.SilkS")
		)
		(fp_rect
			(start -0.508 0.9398)
			(end 0.508 -0.9398)
			(stroke
				(width 0)
				(type default)
			)
			(fill no)
			(layer "F.CrtYd")
		)
		(fp_rect
			(start -0.508 0.9398)
			(end 0.508 -0.9398)
			(stroke
				(width 0)
				(type default)
			)
			(fill no)
			(layer "F.Fab")
		)
		(pad "1" smd custom
			(at 0 -0.4445 90)
			(size 0.1397 0.1397)
			(layers "F.Cu" "F.Mask" "F.Paste")
			(net "P3V3")
			(options
				(clearance outline)
				(anchor circle)
			)
			(primitives
				(gr_poly
					(pts
						(arc
							(start -0.1778 -0.2794)
							(mid -0.249642 -0.249642)
							(end -0.2794 -0.1778)
						)
						(arc
							(start -0.2794 0.1778)
							(mid -0.249642 0.249642)
							(end -0.1778 0.2794)
						)
						(arc
							(start 0.1778 0.2794)
							(mid 0.249642 0.249642)
							(end 0.2794 0.1778)
						)
						(arc
							(start 0.2794 -0.1778)
							(mid 0.249642 -0.249642)
							(end 0.1778 -0.2794)
						)
					)
					(width 0)
					(fill yes)
				)
			)
		)
		(pad "2" smd custom
			(at 0 0.4445 90)
			(size 0.1397 0.1397)
			(layers "F.Cu" "F.Mask" "F.Paste")
			(net "SSD_PRSNT_NET13")
			(options
				(clearance outline)
				(anchor circle)
			)
			(primitives
				(gr_poly
					(pts
						(arc
							(start -0.1778 -0.2794)
							(mid -0.249642 -0.249642)
							(end -0.2794 -0.1778)
						)
						(arc
							(start -0.2794 0.1778)
							(mid -0.249642 0.249642)
							(end -0.1778 0.2794)
						)
						(arc
							(start 0.1778 0.2794)
							(mid 0.249642 0.249642)
							(end 0.2794 0.1778)
						)
						(arc
							(start 0.2794 -0.1778)
							(mid 0.249642 -0.249642)
							(end 0.1778 -0.2794)
						)
					)
					(width 0)
					(fill yes)
				)
			)
		)
	)
	(footprint ""
		(layer "F.Cu")
		(at 52.2224 -245.231158 -90)
		(property "Reference" "R9919"
			(at 0 0 270)
			(layer "F.SilkS")
			(hide yes)
			(effects
				(font
					(size 1.27 1.27)
				)
			)
		)
		(property "Value" "47KR2J-2-GP"
			(at 0.064008 -3.993896 270)
			(unlocked yes)
			(layer "F.Fab")
			(hide yes)
			(effects
				(font
					(size 1.016 1.016)
					(thickness 0.1524)
				)
			)
		)
		(property "Device Type" "R402H16"
			(at 0.064008 -5.517896 270)
			(unlocked yes)
			(layer "F.Fab")
			(hide yes)
			(effects
				(font
					(size 1.016 1.016)
					(thickness 0.1524)
				)
			)
		)
		(duplicate_pad_numbers_are_jumpers no)
		(fp_line
			(start -0.508 -0.9398)
			(end -0.508 0.9398)
			(stroke
				(width 0.1524)
				(type default)
			)
			(layer "F.SilkS")
		)
		(fp_line
			(start 0.508 -0.9398)
			(end -0.508 -0.9398)
			(stroke
				(width 0.1524)
				(type default)
			)
			(layer "F.SilkS")
		)
		(fp_rect
			(start -0.508 0.9398)
			(end 0.508 -0.9398)
			(stroke
				(width 0)
				(type default)
			)
			(fill no)
			(layer "F.CrtYd")
		)
		(fp_rect
			(start -0.508 0.9398)
			(end 0.508 -0.9398)
			(stroke
				(width 0)
				(type default)
			)
			(fill no)
			(layer "F.Fab")
		)
		(pad "1" smd custom
			(at 0 -0.4445 270)
			(size 0.1397 0.1397)
			(layers "F.Cu" "F.Mask" "F.Paste")
			(net "P3V3")
			(options
				(clearance outline)
				(anchor circle)
			)
			(primitives
				(gr_poly
					(pts
						(arc
							(start -0.1778 -0.2794)
							(mid -0.249642 -0.249642)
							(end -0.2794 -0.1778)
						)
						(arc
							(start -0.2794 0.1778)
							(mid -0.249642 0.249642)
							(end -0.1778 0.2794)
						)
						(arc
							(start 0.1778 0.2794)
							(mid 0.249642 0.249642)
							(end 0.2794 0.1778)
						)
						(arc
							(start 0.2794 -0.1778)
							(mid 0.249642 -0.249642)
							(end 0.1778 -0.2794)
						)
					)
					(width 0)
					(fill yes)
				)
			)
		)
		(pad "2" smd custom
			(at 0 0.4445 270)
			(size 0.1397 0.1397)
			(layers "F.Cu" "F.Mask" "F.Paste")
			(net "ATTN_LED_DR7_N")
			(options
				(clearance outline)
				(anchor circle)
			)
			(primitives
				(gr_poly
					(pts
						(arc
							(start -0.1778 -0.2794)
							(mid -0.249642 -0.249642)
							(end -0.2794 -0.1778)
						)
						(arc
							(start -0.2794 0.1778)
							(mid -0.249642 0.249642)
							(end -0.1778 0.2794)
						)
						(arc
							(start 0.1778 0.2794)
							(mid 0.249642 0.249642)
							(end 0.2794 0.1778)
						)
						(arc
							(start 0.2794 -0.1778)
							(mid 0.249642 -0.249642)
							(end 0.1778 -0.2794)
						)
					)
					(width 0)
					(fill yes)
				)
			)
		)
	)
	(footprint ""
		(layer "F.Cu")
		(at 208.534 -403.225)
		(property "Reference" "R9761"
			(at 0 0 0)
			(layer "F.SilkS")
			(hide yes)
			(effects
				(font
					(size 1.27 1.27)
				)
			)
		)
		(property "Value" "4K7R2J-2-GP"
			(at 0.064008 -3.993896 0)
			(unlocked yes)
			(layer "F.Fab")
			(hide yes)
			(effects
				(font
					(size 1.016 1.016)
					(thickness 0.1524)
				)
			)
		)
		(property "Device Type" "R402H16"
			(at 0.064008 -5.517896 0)
			(unlocked yes)
			(layer "F.Fab")
			(hide yes)
			(effects
				(font
					(size 1.016 1.016)
					(thickness 0.1524)
				)
			)
		)
		(duplicate_pad_numbers_are_jumpers no)
		(fp_line
			(start -0.508 -0.9398)
			(end -0.508 0.9398)
			(stroke
				(width 0.1524)
				(type default)
			)
			(layer "F.SilkS")
		)
		(fp_line
			(start 0.508 -0.9398)
			(end -0.508 -0.9398)
			(stroke
				(width 0.1524)
				(type default)
			)
			(layer "F.SilkS")
		)
		(fp_rect
			(start -0.508 0.9398)
			(end 0.508 -0.9398)
			(stroke
				(width 0)
				(type default)
			)
			(fill no)
			(layer "F.CrtYd")
		)
		(fp_rect
			(start -0.508 0.9398)
			(end 0.508 -0.9398)
			(stroke
				(width 0)
				(type default)
			)
			(fill no)
			(layer "F.Fab")
		)
		(pad "1" smd custom
			(at 0 -0.4445)
			(size 0.1397 0.1397)
			(layers "F.Cu" "F.Mask" "F.Paste")
			(net "SSD1_PWREN")
			(options
				(clearance outline)
				(anchor circle)
			)
			(primitives
				(gr_poly
					(pts
						(arc
							(start -0.1778 -0.2794)
							(mid -0.249642 -0.249642)
							(end -0.2794 -0.1778)
						)
						(arc
							(start -0.2794 0.1778)
							(mid -0.249642 0.249642)
							(end -0.1778 0.2794)
						)
						(arc
							(start 0.1778 0.2794)
							(mid 0.249642 0.249642)
							(end 0.2794 0.1778)
						)
						(arc
							(start 0.2794 -0.1778)
							(mid 0.249642 -0.249642)
							(end 0.1778 -0.2794)
						)
					)
					(width 0)
					(fill yes)
				)
			)
		)
		(pad "2" smd custom
			(at 0 0.4445)
			(size 0.1397 0.1397)
			(layers "F.Cu" "F.Mask" "F.Paste")
			(net "GND")
			(options
				(clearance outline)
				(anchor circle)
			)
			(primitives
				(gr_poly
					(pts
						(arc
							(start -0.1778 -0.2794)
							(mid -0.249642 -0.249642)
							(end -0.2794 -0.1778)
						)
						(arc
							(start -0.2794 0.1778)
							(mid -0.249642 0.249642)
							(end -0.1778 0.2794)
						)
						(arc
							(start 0.1778 0.2794)
							(mid 0.249642 0.249642)
							(end 0.2794 0.1778)
						)
						(arc
							(start 0.2794 -0.1778)
							(mid 0.249642 -0.249642)
							(end 0.1778 -0.2794)
						)
					)
					(width 0)
					(fill yes)
				)
			)
		)
	)
	(footprint ""
		(layer "F.Cu")
		(at 219.329 -140.58011 90)
		(property "Reference" "SR1127"
			(at 0 0 90)
			(layer "F.SilkS")
			(hide yes)
			(effects
				(font
					(size 1.27 1.27)
				)
			)
		)
		(property "Value" "4K7R2F-GP"
			(at 0.064008 -3.993896 90)
			(unlocked yes)
			(layer "F.Fab")
			(hide yes)
			(effects
				(font
					(size 1.016 1.016)
					(thickness 0.1524)
				)
			)
		)
		(property "Device Type" "R402H16"
			(at 0.064008 -5.517896 90)
			(unlocked yes)
			(layer "F.Fab")
			(hide yes)
			(effects
				(font
					(size 1.016 1.016)
					(thickness 0.1524)
				)
			)
		)
		(duplicate_pad_numbers_are_jumpers no)
		(fp_line
			(start 0.508 -0.9398)
			(end -0.508 -0.9398)
			(stroke
				(width 0.1524)
				(type default)
			)
			(layer "F.SilkS")
		)
		(fp_line
			(start -0.508 -0.9398)
			(end -0.508 0.9398)
			(stroke
				(width 0.1524)
				(type default)
			)
			(layer "F.SilkS")
		)
		(fp_rect
			(start -0.508 0.9398)
			(end 0.508 -0.9398)
			(stroke
				(width 0)
				(type default)
			)
			(fill no)
			(layer "F.CrtYd")
		)
		(fp_rect
			(start -0.508 0.9398)
			(end 0.508 -0.9398)
			(stroke
				(width 0)
				(type default)
			)
			(fill no)
			(layer "F.Fab")
		)
		(pad "1" smd custom
			(at 0 -0.4445 90)
			(size 0.1397 0.1397)
			(layers "F.Cu" "F.Mask" "F.Paste")
			(net "P3V3")
			(options
				(clearance outline)
				(anchor circle)
			)
			(primitives
				(gr_poly
					(pts
						(arc
							(start -0.1778 -0.2794)
							(mid -0.249642 -0.249642)
							(end -0.2794 -0.1778)
						)
						(arc
							(start -0.2794 0.1778)
							(mid -0.249642 0.249642)
							(end -0.1778 0.2794)
						)
						(arc
							(start 0.1778 0.2794)
							(mid 0.249642 0.249642)
							(end 0.2794 0.1778)
						)
						(arc
							(start 0.2794 -0.1778)
							(mid 0.249642 -0.249642)
							(end 0.1778 -0.2794)
						)
					)
					(width 0)
					(fill yes)
				)
			)
		)
		(pad "2" smd custom
			(at 0 0.4445 90)
			(size 0.1397 0.1397)
			(layers "F.Cu" "F.Mask" "F.Paste")
			(net "SSD3_CLK0_OE_MOS_N")
			(options
				(clearance outline)
				(anchor circle)
			)
			(primitives
				(gr_poly
					(pts
						(arc
							(start -0.1778 -0.2794)
							(mid -0.249642 -0.249642)
							(end -0.2794 -0.1778)
						)
						(arc
							(start -0.2794 0.1778)
							(mid -0.249642 0.249642)
							(end -0.1778 0.2794)
						)
						(arc
							(start 0.1778 0.2794)
							(mid 0.249642 0.249642)
							(end 0.2794 0.1778)
						)
						(arc
							(start 0.2794 -0.1778)
							(mid 0.249642 -0.249642)
							(end 0.1778 -0.2794)
						)
					)
					(width 0)
					(fill yes)
				)
			)
		)
	)
	(footprint ""
		(layer "F.Cu")
		(at 84.455 -301.371 90)
		(property "Reference" "R422"
			(at 0 0 90)
			(layer "F.SilkS")
			(hide yes)
			(effects
				(font
					(size 1.27 1.27)
				)
			)
		)
		(property "Value" "0R2J-2-GP"
			(at 0.064008 -3.993896 90)
			(unlocked yes)
			(layer "F.Fab")
			(hide yes)
			(effects
				(font
					(size 1.016 1.016)
					(thickness 0.1524)
				)
			)
		)
		(property "Device Type" "R402H16"
			(at 0.064008 -5.517896 90)
			(unlocked yes)
			(layer "F.Fab")
			(hide yes)
			(effects
				(font
					(size 1.016 1.016)
					(thickness 0.1524)
				)
			)
		)
		(duplicate_pad_numbers_are_jumpers no)
		(fp_line
			(start 0.508 -0.9398)
			(end -0.508 -0.9398)
			(stroke
				(width 0.1524)
				(type default)
			)
			(layer "F.SilkS")
		)
		(fp_line
			(start -0.508 -0.9398)
			(end -0.508 0.9398)
			(stroke
				(width 0.1524)
				(type default)
			)
			(layer "F.SilkS")
		)
		(fp_rect
			(start -0.508 0.9398)
			(end 0.508 -0.9398)
			(stroke
				(width 0)
				(type default)
			)
			(fill no)
			(layer "F.CrtYd")
		)
		(fp_rect
			(start -0.508 0.9398)
			(end 0.508 -0.9398)
			(stroke
				(width 0)
				(type default)
			)
			(fill no)
			(layer "F.Fab")
		)
		(pad "1" smd custom
			(at 0 -0.4445 90)
			(size 0.1397 0.1397)
			(layers "F.Cu" "F.Mask" "F.Paste")
			(net "BMC_I2C_SDA_BUF_9")
			(options
				(clearance outline)
				(anchor circle)
			)
			(primitives
				(gr_poly
					(pts
						(arc
							(start -0.1778 -0.2794)
							(mid -0.249642 -0.249642)
							(end -0.2794 -0.1778)
						)
						(arc
							(start -0.2794 0.1778)
							(mid -0.249642 0.249642)
							(end -0.1778 0.2794)
						)
						(arc
							(start 0.1778 0.2794)
							(mid 0.249642 0.249642)
							(end 0.2794 0.1778)
						)
						(arc
							(start 0.2794 -0.1778)
							(mid 0.249642 -0.249642)
							(end 0.1778 -0.2794)
						)
					)
					(width 0)
					(fill yes)
				)
			)
		)
		(pad "2" smd custom
			(at 0 0.4445 90)
			(size 0.1397 0.1397)
			(layers "F.Cu" "F.Mask" "F.Paste")
			(net "I2C_SDA_BUF_9_EU2_R")
			(options
				(clearance outline)
				(anchor circle)
			)
			(primitives
				(gr_poly
					(pts
						(arc
							(start -0.1778 -0.2794)
							(mid -0.249642 -0.249642)
							(end -0.2794 -0.1778)
						)
						(arc
							(start -0.2794 0.1778)
							(mid -0.249642 0.249642)
							(end -0.1778 0.2794)
						)
						(arc
							(start 0.1778 0.2794)
							(mid 0.249642 0.249642)
							(end 0.2794 0.1778)
						)
						(arc
							(start 0.2794 -0.1778)
							(mid 0.249642 -0.249642)
							(end 0.1778 -0.2794)
						)
					)
					(width 0)
					(fill yes)
				)
			)
		)
	)
	(footprint ""
		(layer "F.Cu")
		(at 221.0054 -301.5996 -90)
		(property "Reference" "R9792"
			(at 0 0 270)
			(layer "F.SilkS")
			(hide yes)
			(effects
				(font
					(size 1.27 1.27)
				)
			)
		)
		(property "Value" "2K2R5F-GP"
			(at 0 -8.9535 270)
			(unlocked yes)
			(layer "F.Fab")
			(hide yes)
			(effects
				(font
					(size 1.27 1.016)
					(thickness 0.1524)
				)
			)
		)
		(property "Device Type" "R805H24"
			(at 0 -10.6299 270)
			(unlocked yes)
			(layer "F.Fab")
			(hide yes)
			(effects
				(font
					(size 1.27 1.016)
					(thickness 0.1524)
				)
			)
		)
		(duplicate_pad_numbers_are_jumpers no)
		(fp_line
			(start -0.889 1.7018)
			(end 0.889 1.7018)
			(stroke
				(width 0.1524)
				(type default)
			)
			(layer "F.SilkS")
		)
		(fp_line
			(start 0.889 1.7018)
			(end 0.889 -0.508)
			(stroke
				(width 0.1524)
				(type default)
			)
			(layer "F.SilkS")
		)
		(fp_line
			(start -0.889 0.0762)
			(end -0.889 1.7018)
			(stroke
				(width 0.1524)
				(type default)
			)
			(layer "F.SilkS")
		)
		(fp_line
			(start -0.889 -1.7018)
			(end -0.889 0.2794)
			(stroke
				(width 0.1524)
				(type default)
			)
			(layer "F.SilkS")
		)
		(fp_line
			(start 0.889 -1.7018)
			(end 0.889 -0.381)
			(stroke
				(width 0.1524)
				(type default)
			)
			(layer "F.SilkS")
		)
		(fp_line
			(start 0.889 -1.7018)
			(end -0.889 -1.7018)
			(stroke
				(width 0.1524)
				(type default)
			)
			(layer "F.SilkS")
		)
		(fp_poly
			(pts
				(xy 0.9652 -1.778) (xy 0.9652 1.778) (xy -0.9652 1.778) (xy -0.9652 -1.778)
			)
			(stroke
				(width 0)
				(type default)
			)
			(fill no)
			(layer "F.CrtYd")
		)
		(fp_rect
			(start -0.9652 1.778)
			(end 0.9652 -1.778)
			(stroke
				(width 0)
				(type default)
			)
			(fill no)
			(layer "F.Fab")
		)
		(pad "1" smd rect
			(at 0 -0.9652 270)
			(size 1.397 1.143)
			(layers "F.Cu" "F.Mask" "F.Paste")
			(net "P12V_SSD2")
		)
		(pad "2" smd rect
			(at 0 0.9652 270)
			(size 1.397 1.143)
			(layers "F.Cu" "F.Mask" "F.Paste")
			(net "P12V_MOST2_GATE_D")
		)
	)
	(footprint ""
		(layer "F.Cu")
		(at 39.37 -347.48089 180)
		(property "Reference" "Q59"
			(at 0 0 180)
			(layer "F.SilkS")
			(hide yes)
			(effects
				(font
					(size 1.27 1.27)
				)
			)
		)
		(property "Value" "2N7002A-7-GP"
			(at 0.127 -8.9662 180)
			(unlocked yes)
			(layer "F.Fab")
			(hide yes)
			(effects
				(font
					(size 1.016 1.016)
					(thickness 0.1524)
				)
			)
		)
		(property "Device Type" "SOT23DGS2D4H48"
			(at 0.127 -10.4902 180)
			(unlocked yes)
			(layer "F.Fab")
			(hide yes)
			(effects
				(font
					(size 1.016 1.016)
					(thickness 0.1524)
				)
			)
		)
		(duplicate_pad_numbers_are_jumpers no)
		(fp_line
			(start 1.651 1.778)
			(end 1.651 -1.778)
			(stroke
				(width 0.1524)
				(type default)
			)
			(layer "F.SilkS")
		)
		(fp_line
			(start 1.651 -1.778)
			(end -1.651 -1.778)
			(stroke
				(width 0.1524)
				(type default)
			)
			(layer "F.SilkS")
		)
		(fp_line
			(start -1.651 1.778)
			(end 1.651 1.778)
			(stroke
				(width 0.1524)
				(type default)
			)
			(layer "F.SilkS")
		)
		(fp_line
			(start -1.651 -1.778)
			(end -1.651 1.778)
			(stroke
				(width 0.1524)
				(type default)
			)
			(layer "F.SilkS")
		)
		(fp_poly
			(pts
				(xy -1.778 1.8796) (xy -1.778 -1.8796) (xy 1.778 -1.8796) (xy 1.778 1.8796)
			)
			(stroke
				(width 0)
				(type default)
			)
			(fill no)
			(layer "F.CrtYd")
		)
		(fp_poly
			(pts
				(xy -1.778 1.8796) (xy -1.778 -1.8796) (xy 1.778 -1.8796) (xy 1.778 1.8796)
			)
			(stroke
				(width 0)
				(type default)
			)
			(fill no)
			(layer "F.Fab")
		)
		(pad "D" smd custom
			(at 0 -0.9525 180)
			(size 0.1905 0.1905)
			(layers "F.Cu" "F.Mask" "F.Paste")
			(net "SSD6_CLK0_OE_MOS_N")
			(options
				(clearance outline)
				(anchor circle)
			)
			(primitives
				(gr_poly
					(pts
						(arc
							(start -0.1778 0.5715)
							(mid -0.321484 0.511984)
							(end -0.381 0.3683)
						)
						(arc
							(start -0.381 -0.3683)
							(mid -0.321484 -0.511984)
							(end -0.1778 -0.5715)
						)
						(arc
							(start 0.1778 -0.5715)
							(mid 0.321484 -0.511984)
							(end 0.381 -0.3683)
						)
						(arc
							(start 0.381 0.3683)
							(mid 0.321484 0.511984)
							(end 0.1778 0.5715)
						)
					)
					(width 0)
					(fill yes)
				)
			)
		)
		(pad "G" smd custom
			(at -0.98425 0.9525 180)
			(size 0.1905 0.1905)
			(layers "F.Cu" "F.Mask" "F.Paste")
			(net "SSD6_CLK0_OE_R_N")
			(options
				(clearance outline)
				(anchor circle)
			)
			(primitives
				(gr_poly
					(pts
						(arc
							(start -0.1778 0.5715)
							(mid -0.321484 0.511984)
							(end -0.381 0.3683)
						)
						(arc
							(start -0.381 -0.3683)
							(mid -0.321484 -0.511984)
							(end -0.1778 -0.5715)
						)
						(arc
							(start 0.1778 -0.5715)
							(mid 0.321484 -0.511984)
							(end 0.381 -0.3683)
						)
						(arc
							(start 0.381 0.3683)
							(mid 0.321484 0.511984)
							(end 0.1778 0.5715)
						)
					)
					(width 0)
					(fill yes)
				)
			)
		)
		(pad "S" smd custom
			(at 0.98425 0.9525 180)
			(size 0.1905 0.1905)
			(layers "F.Cu" "F.Mask" "F.Paste")
			(net "GND")
			(options
				(clearance outline)
				(anchor circle)
			)
			(primitives
				(gr_poly
					(pts
						(arc
							(start -0.1778 0.5715)
							(mid -0.321484 0.511984)
							(end -0.381 0.3683)
						)
						(arc
							(start -0.381 -0.3683)
							(mid -0.321484 -0.511984)
							(end -0.1778 -0.5715)
						)
						(arc
							(start 0.1778 -0.5715)
							(mid 0.321484 -0.511984)
							(end 0.381 -0.3683)
						)
						(arc
							(start 0.381 0.3683)
							(mid 0.321484 0.511984)
							(end 0.1778 0.5715)
						)
					)
					(width 0)
					(fill yes)
				)
			)
		)
	)
)
